(kicad_pcb
	(version 20260206)
	(generator "pcbnew")
	(generator_version "10.0")
	(general
		(thickness 1.6)
		(legacy_teardrops no)
	)
	(paper "A4")
	(title_block
		(title "04192023_DAF0TMB3IC0_F0TG_MB_C_brd_V02_OCP.brd")
		(comment 1 "Grand Teton / footprints 3676-3682 of 8354")
	)
	(layers
		(0 "F.Cu" signal "TOP")
		(4 "In1.Cu" signal "GND")
		(6 "In2.Cu" signal "IN1")
		(8 "In3.Cu" signal "GND1")
		(10 "In4.Cu" signal "IN2")
		(12 "In5.Cu" signal "GND2")
		(14 "In6.Cu" signal "IN3")
		(16 "In7.Cu" signal "GND3")
		(18 "In8.Cu" signal "VCC")
		(20 "In9.Cu" signal "VCC1")
		(22 "In10.Cu" signal "GND4")
		(24 "In11.Cu" signal "IN4")
		(26 "In12.Cu" signal "GND5")
		(28 "In13.Cu" signal "IN5")
		(30 "In14.Cu" signal "GND6")
		(32 "In15.Cu" signal "IN6")
		(34 "In16.Cu" signal "GND7")
		(2 "B.Cu" signal "BOTTOM")
		(9 "F.Adhes" user "F.Adhesive")
		(11 "B.Adhes" user "B.Adhesive")
		(13 "F.Paste" user "Package Geometry/Pastemask Top")
		(15 "B.Paste" user "Package Geometry/Pastemask Bottom")
		(5 "F.SilkS" user "Ref Des/Silkscreen Top")
		(7 "B.SilkS" user "Ref Des/Silkscreen Bottom")
		(1 "F.Mask" user "Board Geometry/Soldermask Top")
		(3 "B.Mask" user "Board Geometry/Soldermask Bottom")
		(17 "Dwgs.User" user "User.Drawings")
		(19 "Cmts.User" user "User.Comments")
		(21 "Eco1.User" user "User.Eco1")
		(23 "Eco2.User" user "User.Eco2")
		(25 "Edge.Cuts" user "Board Geometry/Outline")
		(27 "Margin" user)
		(31 "F.CrtYd" user "Package Geometry/Place Bound Top")
		(29 "B.CrtYd" user "Package Geometry/Place Bound Bottom")
		(35 "F.Fab" user "Ref Des/Assembly Top")
		(33 "B.Fab" user "Ref Des/Assembly Bottom")
	)
	(footprint ""
		(layer "F.Cu")
		(at 256.87274 -39.082472)
		(property "Reference" "PR4528"
			(at 0 0 0)
			(layer "F.SilkS")
			(hide yes)
			(effects
				(font
					(size 1.27 1.27)
				)
			)
		)
		(property "Value" ""
			(at 0 0 0)
			(layer "F.Fab")
			(effects
				(font
					(size 1.27 1.27)
				)
			)
		)
		(duplicate_pad_numbers_are_jumpers no)
		(fp_line
			(start -0.7874 -0.4064)
			(end 0.7874 -0.4064)
			(stroke
				(width 0.1524)
				(type default)
			)
			(layer "F.SilkS")
		)
		(fp_line
			(start -0.7874 0.4064)
			(end -0.7874 -0.4064)
			(stroke
				(width 0.1524)
				(type default)
			)
			(layer "F.SilkS")
		)
		(fp_line
			(start 0.7874 -0.4064)
			(end 0.7874 0.4064)
			(stroke
				(width 0.1524)
				(type default)
			)
			(layer "F.SilkS")
		)
		(fp_line
			(start 0.7874 0.4064)
			(end -0.7874 0.4064)
			(stroke
				(width 0.1524)
				(type default)
			)
			(layer "F.SilkS")
		)
		(fp_line
			(start -0.67945 -0.305054)
			(end -0.12065 -0.305054)
			(stroke
				(width 0.1)
				(type default)
			)
			(layer "F.Fab")
		)
		(fp_line
			(start -0.67945 0.3048)
			(end -0.67945 -0.305054)
			(stroke
				(width 0.1)
				(type default)
			)
			(layer "F.Fab")
		)
		(fp_line
			(start -0.12065 -0.305054)
			(end -0.12065 -0.2794)
			(stroke
				(width 0.1)
				(type default)
			)
			(layer "F.Fab")
		)
		(fp_line
			(start -0.12065 -0.2794)
			(end 0.12065 -0.2794)
			(stroke
				(width 0.1)
				(type default)
			)
			(layer "F.Fab")
		)
		(fp_line
			(start -0.12065 0.2794)
			(end -0.12065 0.3048)
			(stroke
				(width 0.1)
				(type default)
			)
			(layer "F.Fab")
		)
		(fp_line
			(start -0.12065 0.3048)
			(end -0.67945 0.3048)
			(stroke
				(width 0.1)
				(type default)
			)
			(layer "F.Fab")
		)
		(fp_line
			(start 0.120396 0.2794)
			(end -0.12065 0.2794)
			(stroke
				(width 0.1)
				(type default)
			)
			(layer "F.Fab")
		)
		(fp_line
			(start 0.120396 0.3048)
			(end 0.120396 0.2794)
			(stroke
				(width 0.1)
				(type default)
			)
			(layer "F.Fab")
		)
		(fp_line
			(start 0.12065 -0.3048)
			(end 0.67945 -0.3048)
			(stroke
				(width 0.1)
				(type default)
			)
			(layer "F.Fab")
		)
		(fp_line
			(start 0.12065 -0.2794)
			(end 0.12065 -0.3048)
			(stroke
				(width 0.1)
				(type default)
			)
			(layer "F.Fab")
		)
		(fp_line
			(start 0.67945 -0.3048)
			(end 0.67945 0.3048)
			(stroke
				(width 0.1)
				(type default)
			)
			(layer "F.Fab")
		)
		(fp_line
			(start 0.67945 0.3048)
			(end 0.120396 0.3048)
			(stroke
				(width 0.1)
				(type default)
			)
			(layer "F.Fab")
		)
		(pad "1" smd circle
			(at -0.40005 0)
			(size 0 0)
			(layers "F.Cu" "F.Mask" "F.Paste")
			(net "P12V_E1S_0")
		)
		(pad "2" smd circle
			(at 0.40005 0)
			(size 0 0)
			(layers "F.Cu" "F.Mask" "F.Paste")
			(net "P12V_E1S_GATE_0")
		)
	)
	(footprint ""
		(layer "F.Cu")
		(at 48.683164 -408.517344 -90)
		(property "Reference" "C6629"
			(at 0 0 270)
			(layer "F.SilkS")
			(hide yes)
			(effects
				(font
					(size 1.27 1.27)
				)
			)
		)
		(property "Value" ""
			(at 0 0 270)
			(layer "F.Fab")
			(effects
				(font
					(size 1.27 1.27)
				)
			)
		)
		(duplicate_pad_numbers_are_jumpers no)
		(fp_line
			(start -0.299974 0.150114)
			(end -0.299974 -0.150114)
			(stroke
				(width 0.1)
				(type default)
			)
			(layer "F.Fab")
		)
		(fp_line
			(start 0.299974 0.150114)
			(end -0.299974 0.150114)
			(stroke
				(width 0.1)
				(type default)
			)
			(layer "F.Fab")
		)
		(fp_line
			(start -0.299974 -0.150114)
			(end 0.299974 -0.150114)
			(stroke
				(width 0.1)
				(type default)
			)
			(layer "F.Fab")
		)
		(fp_line
			(start 0.299974 -0.150114)
			(end 0.299974 0.150114)
			(stroke
				(width 0.1)
				(type default)
			)
			(layer "F.Fab")
		)
		(pad "1" smd rect
			(at -0.2667 0 270)
			(size 0.3048 0.381)
			(layers "F.Cu" "F.Mask" "F.Paste")
			(net "P5E_CPU1_P0_TX_BUF_C_DP<0>")
		)
		(pad "2" smd rect
			(at 0.2667 0 270)
			(size 0.3048 0.381)
			(layers "F.Cu" "F.Mask" "F.Paste")
			(net "P5E_CPU1_P0_TX_BUF_DP<0>")
		)
	)
	(footprint ""
		(layer "F.Cu")
		(at 298.050966 -23.763224)
		(property "Reference" "C45"
			(at 0 0 0)
			(layer "F.SilkS")
			(hide yes)
			(effects
				(font
					(size 1.27 1.27)
				)
			)
		)
		(property "Value" ""
			(at 0 0 0)
			(layer "F.Fab")
			(effects
				(font
					(size 1.27 1.27)
				)
			)
		)
		(duplicate_pad_numbers_are_jumpers no)
		(fp_line
			(start -0.7874 -0.4064)
			(end 0.7874 -0.4064)
			(stroke
				(width 0.1524)
				(type default)
			)
			(layer "F.SilkS")
		)
		(fp_line
			(start -0.7874 0.4064)
			(end -0.7874 -0.4064)
			(stroke
				(width 0.1524)
				(type default)
			)
			(layer "F.SilkS")
		)
		(fp_line
			(start 0.7874 -0.4064)
			(end 0.7874 0.4064)
			(stroke
				(width 0.1524)
				(type default)
			)
			(layer "F.SilkS")
		)
		(fp_line
			(start 0.7874 0.4064)
			(end -0.7874 0.4064)
			(stroke
				(width 0.1524)
				(type default)
			)
			(layer "F.SilkS")
		)
		(fp_line
			(start -0.67945 -0.305054)
			(end -0.12065 -0.305054)
			(stroke
				(width 0.1)
				(type default)
			)
			(layer "F.Fab")
		)
		(fp_line
			(start -0.67945 0.3048)
			(end -0.67945 -0.305054)
			(stroke
				(width 0.1)
				(type default)
			)
			(layer "F.Fab")
		)
		(fp_line
			(start -0.12065 -0.305054)
			(end -0.12065 -0.2794)
			(stroke
				(width 0.1)
				(type default)
			)
			(layer "F.Fab")
		)
		(fp_line
			(start -0.12065 -0.2794)
			(end 0.12065 -0.2794)
			(stroke
				(width 0.1)
				(type default)
			)
			(layer "F.Fab")
		)
		(fp_line
			(start -0.12065 0.2794)
			(end -0.12065 0.3048)
			(stroke
				(width 0.1)
				(type default)
			)
			(layer "F.Fab")
		)
		(fp_line
			(start -0.12065 0.3048)
			(end -0.67945 0.3048)
			(stroke
				(width 0.1)
				(type default)
			)
			(layer "F.Fab")
		)
		(fp_line
			(start 0.120396 0.2794)
			(end -0.12065 0.2794)
			(stroke
				(width 0.1)
				(type default)
			)
			(layer "F.Fab")
		)
		(fp_line
			(start 0.120396 0.3048)
			(end 0.120396 0.2794)
			(stroke
				(width 0.1)
				(type default)
			)
			(layer "F.Fab")
		)
		(fp_line
			(start 0.12065 -0.3048)
			(end 0.67945 -0.3048)
			(stroke
				(width 0.1)
				(type default)
			)
			(layer "F.Fab")
		)
		(fp_line
			(start 0.12065 -0.2794)
			(end 0.12065 -0.3048)
			(stroke
				(width 0.1)
				(type default)
			)
			(layer "F.Fab")
		)
		(fp_line
			(start 0.67945 -0.3048)
			(end 0.67945 0.3048)
			(stroke
				(width 0.1)
				(type default)
			)
			(layer "F.Fab")
		)
		(fp_line
			(start 0.67945 0.3048)
			(end 0.120396 0.3048)
			(stroke
				(width 0.1)
				(type default)
			)
			(layer "F.Fab")
		)
		(pad "1" smd circle
			(at -0.40005 0)
			(size 0 0)
			(layers "F.Cu" "F.Mask" "F.Paste")
			(net "P1V5_BAT_IN")
		)
		(pad "2" smd circle
			(at 0.40005 0)
			(size 0 0)
			(layers "F.Cu" "F.Mask" "F.Paste")
			(net "GND")
		)
	)
	(footprint ""
		(layer "F.Cu")
		(at 204.7621 -407.068782 180)
		(property "Reference" "PR1134"
			(at 0 0 180)
			(layer "F.SilkS")
			(hide yes)
			(effects
				(font
					(size 1.27 1.27)
				)
			)
		)
		(property "Value" ""
			(at 0 0 180)
			(layer "F.Fab")
			(effects
				(font
					(size 1.27 1.27)
				)
			)
		)
		(duplicate_pad_numbers_are_jumpers no)
		(fp_line
			(start 0.7874 0.4064)
			(end -0.7874 0.4064)
			(stroke
				(width 0.1524)
				(type default)
			)
			(layer "F.SilkS")
		)
		(fp_line
			(start 0.7874 -0.4064)
			(end 0.7874 0.4064)
			(stroke
				(width 0.1524)
				(type default)
			)
			(layer "F.SilkS")
		)
		(fp_line
			(start -0.7874 0.4064)
			(end -0.7874 -0.4064)
			(stroke
				(width 0.1524)
				(type default)
			)
			(layer "F.SilkS")
		)
		(fp_line
			(start -0.7874 -0.4064)
			(end 0.7874 -0.4064)
			(stroke
				(width 0.1524)
				(type default)
			)
			(layer "F.SilkS")
		)
		(fp_line
			(start 0.67945 0.3048)
			(end 0.120396 0.3048)
			(stroke
				(width 0.1)
				(type default)
			)
			(layer "F.Fab")
		)
		(fp_line
			(start 0.67945 -0.3048)
			(end 0.67945 0.3048)
			(stroke
				(width 0.1)
				(type default)
			)
			(layer "F.Fab")
		)
		(fp_line
			(start 0.12065 -0.2794)
			(end 0.12065 -0.3048)
			(stroke
				(width 0.1)
				(type default)
			)
			(layer "F.Fab")
		)
		(fp_line
			(start 0.12065 -0.3048)
			(end 0.67945 -0.3048)
			(stroke
				(width 0.1)
				(type default)
			)
			(layer "F.Fab")
		)
		(fp_line
			(start 0.120396 0.3048)
			(end 0.120396 0.2794)
			(stroke
				(width 0.1)
				(type default)
			)
			(layer "F.Fab")
		)
		(fp_line
			(start 0.120396 0.2794)
			(end -0.12065 0.2794)
			(stroke
				(width 0.1)
				(type default)
			)
			(layer "F.Fab")
		)
		(fp_line
			(start -0.12065 0.3048)
			(end -0.67945 0.3048)
			(stroke
				(width 0.1)
				(type default)
			)
			(layer "F.Fab")
		)
		(fp_line
			(start -0.12065 0.2794)
			(end -0.12065 0.3048)
			(stroke
				(width 0.1)
				(type default)
			)
			(layer "F.Fab")
		)
		(fp_line
			(start -0.12065 -0.2794)
			(end 0.12065 -0.2794)
			(stroke
				(width 0.1)
				(type default)
			)
			(layer "F.Fab")
		)
		(fp_line
			(start -0.12065 -0.305054)
			(end -0.12065 -0.2794)
			(stroke
				(width 0.1)
				(type default)
			)
			(layer "F.Fab")
		)
		(fp_line
			(start -0.67945 0.3048)
			(end -0.67945 -0.305054)
			(stroke
				(width 0.1)
				(type default)
			)
			(layer "F.Fab")
		)
		(fp_line
			(start -0.67945 -0.305054)
			(end -0.12065 -0.305054)
			(stroke
				(width 0.1)
				(type default)
			)
			(layer "F.Fab")
		)
		(pad "1" smd circle
			(at -0.40005 0 180)
			(size 0 0)
			(layers "F.Cu" "F.Mask" "F.Paste")
			(net "AGND_HSC")
		)
		(pad "2" smd circle
			(at 0.40005 0 180)
			(size 0 0)
			(layers "F.Cu" "F.Mask" "F.Paste")
			(net "HSC_MODE_1")
		)
	)
	(footprint ""
		(layer "F.Cu")
		(at 393.092178 -180.078634 -90)
		(property "Reference" "PC547"
			(at 0 0 270)
			(layer "F.SilkS")
			(hide yes)
			(effects
				(font
					(size 1.27 1.27)
				)
			)
		)
		(property "Value" ""
			(at 0 0 270)
			(layer "F.Fab")
			(effects
				(font
					(size 1.27 1.27)
				)
			)
		)
		(duplicate_pad_numbers_are_jumpers no)
		(fp_line
			(start -0.7874 0.4064)
			(end -0.7874 -0.4064)
			(stroke
				(width 0.1524)
				(type default)
			)
			(layer "F.SilkS")
		)
		(fp_line
			(start -0.134366 0.4064)
			(end -0.7874 0.4064)
			(stroke
				(width 0.1524)
				(type default)
			)
			(layer "F.SilkS")
		)
		(fp_line
			(start 0.7874 0.4064)
			(end 0.449834 0.4064)
			(stroke
				(width 0.1524)
				(type default)
			)
			(layer "F.SilkS")
		)
		(fp_line
			(start -0.7874 -0.4064)
			(end 0.7874 -0.4064)
			(stroke
				(width 0.1524)
				(type default)
			)
			(layer "F.SilkS")
		)
		(fp_line
			(start 0.7874 -0.4064)
			(end 0.7874 0.4064)
			(stroke
				(width 0.1524)
				(type default)
			)
			(layer "F.SilkS")
		)
		(fp_line
			(start -0.67945 0.3048)
			(end -0.67945 -0.305054)
			(stroke
				(width 0.1)
				(type default)
			)
			(layer "F.Fab")
		)
		(fp_line
			(start -0.12065 0.3048)
			(end -0.67945 0.3048)
			(stroke
				(width 0.1)
				(type default)
			)
			(layer "F.Fab")
		)
		(fp_line
			(start 0.120396 0.3048)
			(end 0.120396 0.2794)
			(stroke
				(width 0.1)
				(type default)
			)
			(layer "F.Fab")
		)
		(fp_line
			(start 0.67945 0.3048)
			(end 0.120396 0.3048)
			(stroke
				(width 0.1)
				(type default)
			)
			(layer "F.Fab")
		)
		(fp_line
			(start -0.12065 0.2794)
			(end -0.12065 0.3048)
			(stroke
				(width 0.1)
				(type default)
			)
			(layer "F.Fab")
		)
		(fp_line
			(start 0.120396 0.2794)
			(end -0.12065 0.2794)
			(stroke
				(width 0.1)
				(type default)
			)
			(layer "F.Fab")
		)
		(fp_line
			(start -0.12065 -0.2794)
			(end 0.12065 -0.2794)
			(stroke
				(width 0.1)
				(type default)
			)
			(layer "F.Fab")
		)
		(fp_line
			(start 0.12065 -0.2794)
			(end 0.12065 -0.3048)
			(stroke
				(width 0.1)
				(type default)
			)
			(layer "F.Fab")
		)
		(fp_line
			(start 0.12065 -0.3048)
			(end 0.67945 -0.3048)
			(stroke
				(width 0.1)
				(type default)
			)
			(layer "F.Fab")
		)
		(fp_line
			(start 0.67945 -0.3048)
			(end 0.67945 0.3048)
			(stroke
				(width 0.1)
				(type default)
			)
			(layer "F.Fab")
		)
		(fp_line
			(start -0.67945 -0.305054)
			(end -0.12065 -0.305054)
			(stroke
				(width 0.1)
				(type default)
			)
			(layer "F.Fab")
		)
		(fp_line
			(start -0.12065 -0.305054)
			(end -0.12065 -0.2794)
			(stroke
				(width 0.1)
				(type default)
			)
			(layer "F.Fab")
		)
		(pad "1" smd circle
			(at -0.40005 0 270)
			(size 0 0)
			(layers "F.Cu" "F.Mask" "F.Paste")
			(net "PVDDCR_CPU0_P0_VCC4")
		)
		(pad "2" smd circle
			(at 0.40005 0 270)
			(size 0 0)
			(layers "F.Cu" "F.Mask" "F.Paste")
			(net "GND")
		)
	)
	(footprint ""
		(layer "F.Cu")
		(at 45.94606 -351.372932 90)
		(property "Reference" "PR278"
			(at 0 0 90)
			(layer "F.SilkS")
			(hide yes)
			(effects
				(font
					(size 1.27 1.27)
				)
			)
		)
		(property "Value" ""
			(at 0 0 90)
			(layer "F.Fab")
			(effects
				(font
					(size 1.27 1.27)
				)
			)
		)
		(duplicate_pad_numbers_are_jumpers no)
		(fp_line
			(start 0.7874 -0.4064)
			(end 0.7874 0.4064)
			(stroke
				(width 0.1524)
				(type default)
			)
			(layer "F.SilkS")
		)
		(fp_line
			(start -0.7874 -0.4064)
			(end 0.7874 -0.4064)
			(stroke
				(width 0.1524)
				(type default)
			)
			(layer "F.SilkS")
		)
		(fp_line
			(start 0.7874 0.4064)
			(end -0.7874 0.4064)
			(stroke
				(width 0.1524)
				(type default)
			)
			(layer "F.SilkS")
		)
		(fp_line
			(start -0.7874 0.4064)
			(end -0.7874 -0.4064)
			(stroke
				(width 0.1524)
				(type default)
			)
			(layer "F.SilkS")
		)
		(fp_line
			(start -0.12065 -0.305054)
			(end -0.12065 -0.2794)
			(stroke
				(width 0.1)
				(type default)
			)
			(layer "F.Fab")
		)
		(fp_line
			(start -0.67945 -0.305054)
			(end -0.12065 -0.305054)
			(stroke
				(width 0.1)
				(type default)
			)
			(layer "F.Fab")
		)
		(fp_line
			(start 0.67945 -0.3048)
			(end 0.67945 0.3048)
			(stroke
				(width 0.1)
				(type default)
			)
			(layer "F.Fab")
		)
		(fp_line
			(start 0.12065 -0.3048)
			(end 0.67945 -0.3048)
			(stroke
				(width 0.1)
				(type default)
			)
			(layer "F.Fab")
		)
		(fp_line
			(start 0.12065 -0.2794)
			(end 0.12065 -0.3048)
			(stroke
				(width 0.1)
				(type default)
			)
			(layer "F.Fab")
		)
		(fp_line
			(start -0.12065 -0.2794)
			(end 0.12065 -0.2794)
			(stroke
				(width 0.1)
				(type default)
			)
			(layer "F.Fab")
		)
		(fp_line
			(start 0.120396 0.2794)
			(end -0.12065 0.2794)
			(stroke
				(width 0.1)
				(type default)
			)
			(layer "F.Fab")
		)
		(fp_line
			(start -0.12065 0.2794)
			(end -0.12065 0.3048)
			(stroke
				(width 0.1)
				(type default)
			)
			(layer "F.Fab")
		)
		(fp_line
			(start 0.67945 0.3048)
			(end 0.120396 0.3048)
			(stroke
				(width 0.1)
				(type default)
			)
			(layer "F.Fab")
		)
		(fp_line
			(start 0.120396 0.3048)
			(end 0.120396 0.2794)
			(stroke
				(width 0.1)
				(type default)
			)
			(layer "F.Fab")
		)
		(fp_line
			(start -0.12065 0.3048)
			(end -0.67945 0.3048)
			(stroke
				(width 0.1)
				(type default)
			)
			(layer "F.Fab")
		)
		(fp_line
			(start -0.67945 0.3048)
			(end -0.67945 -0.305054)
			(stroke
				(width 0.1)
				(type default)
			)
			(layer "F.Fab")
		)
		(pad "1" smd circle
			(at -0.40005 0 90)
			(size 0 0)
			(layers "F.Cu" "F.Mask" "F.Paste")
			(net "SW_PVDDIO_P1_BOOT2")
		)
		(pad "2" smd circle
			(at 0.40005 0 90)
			(size 0 0)
			(layers "F.Cu" "F.Mask" "F.Paste")
			(net "SW_PVDDIO_P1_BOOT2_R")
		)
	)
	(footprint ""
		(layer "F.Cu")
		(at 165.509448 -51.81346 -90)
		(property "Reference" "C1920"
			(at 0 0 270)
			(layer "F.SilkS")
			(hide yes)
			(effects
				(font
					(size 1.27 1.27)
				)
			)
		)
		(property "Value" ""
			(at 0 0 270)
			(layer "F.Fab")
			(effects
				(font
					(size 1.27 1.27)
				)
			)
		)
		(duplicate_pad_numbers_are_jumpers no)
		(fp_line
			(start -1.2954 0.5842)
			(end -1.2954 -0.5842)
			(stroke
				(width 0.1524)
				(type default)
			)
			(layer "F.SilkS")
		)
		(fp_line
			(start 1.2954 0.5842)
			(end -1.2954 0.5842)
			(stroke
				(width 0.1524)
				(type default)
			)
			(layer "F.SilkS")
		)
		(fp_line
			(start -1.2954 -0.5842)
			(end 1.2954 -0.5842)
			(stroke
				(width 0.1524)
				(type default)
			)
			(layer "F.SilkS")
		)
		(fp_line
			(start 1.2954 -0.5842)
			(end 1.2954 0.5842)
			(stroke
				(width 0.1524)
				(type default)
			)
			(layer "F.SilkS")
		)
		(fp_line
			(start -0.8636 0.4572)
			(end -0.8636 0.4064)
			(stroke
				(width 0.1)
				(type default)
			)
			(layer "F.Fab")
		)
		(fp_line
			(start 0.8636 0.4572)
			(end -0.8636 0.4572)
			(stroke
				(width 0.1)
				(type default)
			)
			(layer "F.Fab")
		)
		(fp_line
			(start -1.1938 0.4064)
			(end -1.1938 -0.4064)
			(stroke
				(width 0.1)
				(type default)
			)
			(layer "F.Fab")
		)
		(fp_line
			(start -0.8636 0.4064)
			(end -1.1938 0.4064)
			(stroke
				(width 0.1)
				(type default)
			)
			(layer "F.Fab")
		)
		(fp_line
			(start 0.8636 0.4064)
			(end 0.8636 0.4572)
			(stroke
				(width 0.1)
				(type default)
			)
			(layer "F.Fab")
		)
		(fp_line
			(start 1.1938 0.4064)
			(end 0.8636 0.4064)
			(stroke
				(width 0.1)
				(type default)
			)
			(layer "F.Fab")
		)
		(fp_line
			(start -1.1938 -0.4064)
			(end -0.8636 -0.4064)
			(stroke
				(width 0.1)
				(type default)
			)
			(layer "F.Fab")
		)
		(fp_line
			(start -0.8636 -0.4064)
			(end -0.8636 -0.4572)
			(stroke
				(width 0.1)
				(type default)
			)
			(layer "F.Fab")
		)
		(fp_line
			(start 0.8636 -0.4064)
			(end 1.1938 -0.4064)
			(stroke
				(width 0.1)
				(type default)
			)
			(layer "F.Fab")
		)
		(fp_line
			(start 1.1938 -0.4064)
			(end 1.1938 0.4064)
			(stroke
				(width 0.1)
				(type default)
			)
			(layer "F.Fab")
		)
		(fp_line
			(start -0.8636 -0.4572)
			(end 0.8636 -0.4572)
			(stroke
				(width 0.1)
				(type default)
			)
			(layer "F.Fab")
		)
		(fp_line
			(start 0.8636 -0.4572)
			(end 0.8636 -0.4064)
			(stroke
				(width 0.1)
				(type default)
			)
			(layer "F.Fab")
		)
		(pad "1" smd rect
			(at -0.7366 0 180)
			(size 0.7112 0.8128)
			(layers "F.Cu" "F.Mask" "F.Paste")
			(net "P3V3_M2_0")
		)
		(pad "2" smd rect
			(at 0.7366 0 180)
			(size 0.7112 0.8128)
			(layers "F.Cu" "F.Mask" "F.Paste")
			(net "GND")
		)
	)
)
